FILE_TYPE = MACRO_DRAWING;
SET COLOR_WIRE YELLOW;
SET COLOR_PROP MONO;
SET COLOR_DOT WHITE;
SET COLOR_ARC YELLOW;
SET COLOR_BODY GREEN;
SET COLOR_NOTE MONO;
SET PROP_DISPLAY VALUE;
SET PAGE_NUMBER P245;
FORCEADD OFFPAGE..3
R 2
(-5500 2075);
FORCEPROP 2 LAST $XR0 115 
J 0
(-5780 2075);
DISPLAY 0.638298 (-5780 2075);
PAINT MONO (-5780 2075);
FORCEPROP 1 LAST COMMENT_BODY TRUE
J 2
(-5450 1975);
DISPLAY 1.170213 (-5450 1975);
PAINT GREEN (-5450 1975);
DISPLAY INVISIBLE (-5450 1975);
FORCEPROP 1 LAST OFFPAGE TRUE
J 2
(-5825 1950);
PAINT GREEN (-5825 1950);
DISPLAY INVISIBLE (-5825 1950);
FORCEPROP 2 LAST PATH I1
J 0
(-5775 2125);
DISPLAY 1.021277 (-5775 2125);
PAINT ORANGE (-5775 2125);
DISPLAY INVISIBLE (-5775 2125);
FORCEPROP 2 LAST BOM_COST SM_CONTROLLER
J 2
(-5975 2125);
PAINT MONO (-5975 2125);
DISPLAY INVISIBLE (-5975 2125);
FORCEPROP 2 LAST ROOM BMC
J 2
(-5975 2125);
PAINT MONO (-5975 2125);
DISPLAY INVISIBLE (-5975 2125);
FORCEPROP 2 LAST CDS_LIB mstr_standard
J 0
(-5500 2075);
PAINT MONO (-5500 2075);
DISPLAY INVISIBLE (-5500 2075);
FORCEADD TAP..1
R 2
(-5925 2925);
FORCEPROP 3 LASTPIN (-5875 2925) SIG_NAME P3E_CPU0_PE2_SS_C_TXN<11>
J 0
(-5865 2935);
DISPLAY 0.659574 (-5865 2935);
PAINT MONO (-5865 2935);
DISPLAY INVISIBLE (-5865 2935);
FORCEPROP 1 LASTPIN (-5875 2925) BN 11
J 2
(-5863 2933);
DISPLAY 0.680851 (-5863 2933);
PAINT GREEN (-5863 2933);
FORCEPROP 1 LAST HDL_TAP TRUE
J 2
(-6250 2800);
DISPLAY 0.872340 (-6250 2800);
PAINT ORANGE (-6250 2800);
DISPLAY INVISIBLE (-6250 2800);
FORCEPROP 1 LAST BODY_TYPE PLUMBING
J 2
(-5925 2975);
DISPLAY 0.872340 (-5925 2975);
PAINT GREEN (-5925 2975);
DISPLAY INVISIBLE (-5925 2975);
FORCEPROP 1 LAST PATH I10
J 2
(-5923 2925);
DISPLAY 0.872340 (-5923 2925);
PAINT GREEN (-5923 2925);
DISPLAY INVISIBLE (-5923 2925);
FORCEPROP 2 LAST CDS_LIB mstr_standard
J 0
(-5925 2925);
PAINT MONO (-5925 2925);
DISPLAY INVISIBLE (-5925 2925);
FORCEADD TAP..1
R 2
(-5925 3125);
FORCEPROP 3 LASTPIN (-5875 3125) SIG_NAME P3E_CPU0_PE2_SS_C_TXN<10>
J 0
(-5865 3135);
DISPLAY 0.659574 (-5865 3135);
PAINT MONO (-5865 3135);
DISPLAY INVISIBLE (-5865 3135);
FORCEPROP 1 LASTPIN (-5875 3125) BN 10
J 2
(-5863 3133);
DISPLAY 0.680851 (-5863 3133);
PAINT GREEN (-5863 3133);
FORCEPROP 1 LAST HDL_TAP TRUE
J 2
(-6250 3000);
DISPLAY 0.872340 (-6250 3000);
PAINT ORANGE (-6250 3000);
DISPLAY INVISIBLE (-6250 3000);
FORCEPROP 1 LAST BODY_TYPE PLUMBING
J 2
(-5925 3175);
DISPLAY 0.872340 (-5925 3175);
PAINT GREEN (-5925 3175);
DISPLAY INVISIBLE (-5925 3175);
FORCEPROP 1 LAST PATH I11
J 2
(-5923 3125);
DISPLAY 0.872340 (-5923 3125);
PAINT GREEN (-5923 3125);
DISPLAY INVISIBLE (-5923 3125);
FORCEPROP 2 LAST CDS_LIB mstr_standard
J 0
(-5925 3125);
PAINT MONO (-5925 3125);
DISPLAY INVISIBLE (-5925 3125);
FORCEADD TAP..1
R 2
(-5925 3275);
FORCEPROP 3 LASTPIN (-5875 3275) SIG_NAME P3E_CPU0_PE2_SS_C_TXN<9>
J 0
(-5865 3285);
DISPLAY 0.659574 (-5865 3285);
PAINT MONO (-5865 3285);
DISPLAY INVISIBLE (-5865 3285);
FORCEPROP 1 LASTPIN (-5875 3275) BN 9
J 2
(-5863 3283);
DISPLAY 0.680851 (-5863 3283);
PAINT GREEN (-5863 3283);
FORCEPROP 1 LAST HDL_TAP TRUE
J 2
(-6250 3150);
DISPLAY 0.872340 (-6250 3150);
PAINT ORANGE (-6250 3150);
DISPLAY INVISIBLE (-6250 3150);
FORCEPROP 1 LAST BODY_TYPE PLUMBING
J 2
(-5925 3325);
DISPLAY 0.872340 (-5925 3325);
PAINT GREEN (-5925 3325);
DISPLAY INVISIBLE (-5925 3325);
FORCEPROP 1 LAST PATH I12
J 2
(-5923 3275);
DISPLAY 0.872340 (-5923 3275);
PAINT GREEN (-5923 3275);
DISPLAY INVISIBLE (-5923 3275);
FORCEPROP 2 LAST CDS_LIB mstr_standard
J 0
(-5925 3275);
PAINT MONO (-5925 3275);
DISPLAY INVISIBLE (-5925 3275);
FORCEADD TAP..1
R 2
(-5300 2525);
FORCEPROP 3 LASTPIN (-5250 2525) SIG_NAME P3E_CPU0_PE2_SS_C_TXP<14>
J 0
(-5240 2535);
DISPLAY 0.659574 (-5240 2535);
PAINT MONO (-5240 2535);
DISPLAY INVISIBLE (-5240 2535);
FORCEPROP 1 LASTPIN (-5250 2525) BN 14
J 2
(-5238 2533);
DISPLAY 0.680851 (-5238 2533);
PAINT GREEN (-5238 2533);
FORCEPROP 1 LAST HDL_TAP TRUE
J 2
(-5625 2400);
DISPLAY 0.872340 (-5625 2400);
PAINT ORANGE (-5625 2400);
DISPLAY INVISIBLE (-5625 2400);
FORCEPROP 1 LAST BODY_TYPE PLUMBING
J 2
(-5300 2575);
DISPLAY 0.872340 (-5300 2575);
PAINT GREEN (-5300 2575);
DISPLAY INVISIBLE (-5300 2575);
FORCEPROP 1 LAST PATH I13
J 2
(-5298 2525);
DISPLAY 0.872340 (-5298 2525);
PAINT GREEN (-5298 2525);
DISPLAY INVISIBLE (-5298 2525);
FORCEPROP 2 LAST CDS_LIB mstr_standard
J 0
(-5300 2525);
PAINT MONO (-5300 2525);
DISPLAY INVISIBLE (-5300 2525);
FORCEADD TAP..1
R 2
(-5300 2775);
FORCEPROP 3 LASTPIN (-5250 2775) SIG_NAME P3E_CPU0_PE2_SS_C_TXP<12>
J 0
(-5240 2785);
DISPLAY 0.659574 (-5240 2785);
PAINT MONO (-5240 2785);
DISPLAY INVISIBLE (-5240 2785);
FORCEPROP 1 LASTPIN (-5250 2775) BN 12
J 2
(-5238 2783);
DISPLAY 0.680851 (-5238 2783);
PAINT GREEN (-5238 2783);
FORCEPROP 1 LAST HDL_TAP TRUE
J 2
(-5625 2650);
DISPLAY 0.872340 (-5625 2650);
PAINT ORANGE (-5625 2650);
DISPLAY INVISIBLE (-5625 2650);
FORCEPROP 1 LAST BODY_TYPE PLUMBING
J 2
(-5300 2825);
DISPLAY 0.872340 (-5300 2825);
PAINT GREEN (-5300 2825);
DISPLAY INVISIBLE (-5300 2825);
FORCEPROP 1 LAST PATH I14
J 2
(-5298 2775);
DISPLAY 0.872340 (-5298 2775);
PAINT GREEN (-5298 2775);
DISPLAY INVISIBLE (-5298 2775);
FORCEPROP 2 LAST CDS_LIB mstr_standard
J 0
(-5300 2775);
PAINT MONO (-5300 2775);
DISPLAY INVISIBLE (-5300 2775);
FORCEADD TAP..1
R 2
(-5300 2625);
FORCEPROP 3 LASTPIN (-5250 2625) SIG_NAME P3E_CPU0_PE2_SS_C_TXP<13>
J 0
(-5240 2635);
DISPLAY 0.659574 (-5240 2635);
PAINT MONO (-5240 2635);
DISPLAY INVISIBLE (-5240 2635);
FORCEPROP 1 LASTPIN (-5250 2625) BN 13
J 2
(-5238 2633);
DISPLAY 0.680851 (-5238 2633);
PAINT GREEN (-5238 2633);
FORCEPROP 1 LAST HDL_TAP TRUE
J 2
(-5625 2500);
DISPLAY 0.872340 (-5625 2500);
PAINT ORANGE (-5625 2500);
DISPLAY INVISIBLE (-5625 2500);
FORCEPROP 1 LAST BODY_TYPE PLUMBING
J 2
(-5300 2675);
DISPLAY 0.872340 (-5300 2675);
PAINT GREEN (-5300 2675);
DISPLAY INVISIBLE (-5300 2675);
FORCEPROP 1 LAST PATH I15
J 2
(-5298 2625);
DISPLAY 0.872340 (-5298 2625);
PAINT GREEN (-5298 2625);
DISPLAY INVISIBLE (-5298 2625);
FORCEPROP 2 LAST CDS_LIB mstr_standard
J 0
(-5300 2625);
PAINT MONO (-5300 2625);
DISPLAY INVISIBLE (-5300 2625);
FORCEADD TAP..1
R 2
(-5300 2975);
FORCEPROP 3 LASTPIN (-5250 2975) SIG_NAME P3E_CPU0_PE2_SS_C_TXP<11>
J 0
(-5240 2985);
DISPLAY 0.659574 (-5240 2985);
PAINT MONO (-5240 2985);
DISPLAY INVISIBLE (-5240 2985);
FORCEPROP 1 LASTPIN (-5250 2975) BN 11
J 2
(-5238 2983);
DISPLAY 0.680851 (-5238 2983);
PAINT GREEN (-5238 2983);
FORCEPROP 1 LAST HDL_TAP TRUE
J 2
(-5625 2850);
DISPLAY 0.872340 (-5625 2850);
PAINT ORANGE (-5625 2850);
DISPLAY INVISIBLE (-5625 2850);
FORCEPROP 1 LAST BODY_TYPE PLUMBING
J 2
(-5300 3025);
DISPLAY 0.872340 (-5300 3025);
PAINT GREEN (-5300 3025);
DISPLAY INVISIBLE (-5300 3025);
FORCEPROP 1 LAST PATH I16
J 2
(-5298 2975);
DISPLAY 0.872340 (-5298 2975);
PAINT GREEN (-5298 2975);
DISPLAY INVISIBLE (-5298 2975);
FORCEPROP 2 LAST CDS_LIB mstr_standard
J 0
(-5300 2975);
PAINT MONO (-5300 2975);
DISPLAY INVISIBLE (-5300 2975);
FORCEADD TAP..1
R 2
(-5300 3075);
FORCEPROP 3 LASTPIN (-5250 3075) SIG_NAME P3E_CPU0_PE2_SS_C_TXP<10>
J 0
(-5240 3085);
DISPLAY 0.659574 (-5240 3085);
PAINT MONO (-5240 3085);
DISPLAY INVISIBLE (-5240 3085);
FORCEPROP 1 LASTPIN (-5250 3075) BN 10
J 2
(-5238 3083);
DISPLAY 0.680851 (-5238 3083);
PAINT GREEN (-5238 3083);
FORCEPROP 1 LAST HDL_TAP TRUE
J 2
(-5625 2950);
DISPLAY 0.872340 (-5625 2950);
PAINT ORANGE (-5625 2950);
DISPLAY INVISIBLE (-5625 2950);
FORCEPROP 1 LAST BODY_TYPE PLUMBING
J 2
(-5300 3125);
DISPLAY 0.872340 (-5300 3125);
PAINT GREEN (-5300 3125);
DISPLAY INVISIBLE (-5300 3125);
FORCEPROP 1 LAST PATH I17
J 2
(-5298 3075);
DISPLAY 0.872340 (-5298 3075);
PAINT GREEN (-5298 3075);
DISPLAY INVISIBLE (-5298 3075);
FORCEPROP 2 LAST CDS_LIB mstr_standard
J 0
(-5300 3075);
PAINT MONO (-5300 3075);
DISPLAY INVISIBLE (-5300 3075);
FORCEADD TAP..1
R 2
(-5300 3225);
FORCEPROP 3 LASTPIN (-5250 3225) SIG_NAME P3E_CPU0_PE2_SS_C_TXP<9>
J 0
(-5240 3235);
DISPLAY 0.659574 (-5240 3235);
PAINT MONO (-5240 3235);
DISPLAY INVISIBLE (-5240 3235);
FORCEPROP 1 LASTPIN (-5250 3225) BN 9
J 2
(-5238 3233);
DISPLAY 0.680851 (-5238 3233);
PAINT GREEN (-5238 3233);
FORCEPROP 1 LAST HDL_TAP TRUE
J 2
(-5625 3100);
DISPLAY 0.872340 (-5625 3100);
PAINT ORANGE (-5625 3100);
DISPLAY INVISIBLE (-5625 3100);
FORCEPROP 1 LAST BODY_TYPE PLUMBING
J 2
(-5300 3275);
DISPLAY 0.872340 (-5300 3275);
PAINT GREEN (-5300 3275);
DISPLAY INVISIBLE (-5300 3275);
FORCEPROP 1 LAST PATH I18
J 2
(-5298 3225);
DISPLAY 0.872340 (-5298 3225);
PAINT GREEN (-5298 3225);
DISPLAY INVISIBLE (-5298 3225);
FORCEPROP 2 LAST CDS_LIB mstr_standard
J 0
(-5300 3225);
PAINT MONO (-5300 3225);
DISPLAY INVISIBLE (-5300 3225);
FORCEADD GND..1
(-4750 1825);
FORCEPROP 3 LASTPIN (-4750 1875) SIG_NAME GND\g
J 0
(-4740 1885);
DISPLAY 0.659574 (-4740 1885);
PAINT MONO (-4740 1885);
DISPLAY INVISIBLE (-4740 1885);
FORCEPROP 1 LAST HDL_POWER GND
J 0
(-4750 2050);
DISPLAY 0.893617 (-4750 2050);
PAINT GREEN (-4750 2050);
DISPLAY INVISIBLE (-4750 2050);
FORCEPROP 1 LAST BODY_TYPE PLUMBING
J 0
(-4795 1782);
DISPLAY 0.340426 (-4795 1782);
PAINT GREEN (-4795 1782);
DISPLAY INVISIBLE (-4795 1782);
FORCEPROP 1 LAST PATH I19
J 0
(-4675 1825);
DISPLAY 0.872340 (-4675 1825);
PAINT AQUA (-4675 1825);
DISPLAY INVISIBLE (-4675 1825);
FORCEPROP 2 LAST CDS_LIB mstr_symbols
J 0
(-4750 1825);
PAINT MONO (-4750 1825);
DISPLAY INVISIBLE (-4750 1825);
FORCEPROP 2 LAST BOM_COST PVPP_KLM_VR
J 0
(-5650 1975);
DISPLAY 1.042553 (-5650 1975);
PAINT WHITE (-5650 1975);
DISPLAY INVISIBLE (-5650 1975);
FORCEPROP 1 LAST VOLTAGE 0
J 0
(-4750 1900);
PAINT SKYBLUE (-4750 1900);
DISPLAY INVISIBLE (-4750 1900);
FORCEPROP 1 LAST SIZE 1B
J 0
(-4675 1850);
DISPLAY 0.893617 (-4675 1850);
PAINT GREEN (-4675 1850);
DISPLAY INVISIBLE (-4675 1850);
FORCEPROP 2 LAST ROOM PVPP_KLM_VR
J 0
(-5400 1975);
PAINT GREEN (-5400 1975);
DISPLAY INVISIBLE (-5400 1975);
FORCEADD OFFPAGE..3
R 2
(-5500 2025);
FORCEPROP 2 LAST $XR0 115 
J 0
(-5780 2025);
DISPLAY 0.638298 (-5780 2025);
PAINT MONO (-5780 2025);
FORCEPROP 1 LAST COMMENT_BODY TRUE
J 2
(-5450 1925);
DISPLAY 1.170213 (-5450 1925);
PAINT GREEN (-5450 1925);
DISPLAY INVISIBLE (-5450 1925);
FORCEPROP 1 LAST OFFPAGE TRUE
J 2
(-5825 1900);
PAINT GREEN (-5825 1900);
DISPLAY INVISIBLE (-5825 1900);
FORCEPROP 2 LAST PATH I2
J 0
(-5775 2075);
DISPLAY 1.021277 (-5775 2075);
PAINT ORANGE (-5775 2075);
DISPLAY INVISIBLE (-5775 2075);
FORCEPROP 2 LAST ROOM BMC
J 2
(-5975 2075);
PAINT MONO (-5975 2075);
DISPLAY INVISIBLE (-5975 2075);
FORCEPROP 2 LAST BOM_COST SM_CONTROLLER
J 2
(-5975 2075);
PAINT MONO (-5975 2075);
DISPLAY INVISIBLE (-5975 2075);
FORCEPROP 2 LAST CDS_LIB mstr_standard
J 0
(-5500 2025);
PAINT MONO (-5500 2025);
DISPLAY INVISIBLE (-5500 2025);
FORCEADD GND..1
(-4300 1625);
FORCEPROP 3 LASTPIN (-4300 1675) SIG_NAME GND\g
J 0
(-4290 1685);
DISPLAY 0.659574 (-4290 1685);
PAINT MONO (-4290 1685);
DISPLAY INVISIBLE (-4290 1685);
FORCEPROP 1 LAST HDL_POWER GND
J 0
(-4300 1850);
DISPLAY 0.893617 (-4300 1850);
PAINT GREEN (-4300 1850);
DISPLAY INVISIBLE (-4300 1850);
FORCEPROP 1 LAST BODY_TYPE PLUMBING
J 0
(-4345 1582);
DISPLAY 0.340426 (-4345 1582);
PAINT GREEN (-4345 1582);
DISPLAY INVISIBLE (-4345 1582);
FORCEPROP 1 LAST PATH I20
J 0
(-4225 1625);
DISPLAY 0.872340 (-4225 1625);
PAINT AQUA (-4225 1625);
DISPLAY INVISIBLE (-4225 1625);
FORCEPROP 2 LAST CDS_LIB mstr_symbols
J 0
(-4300 1625);
PAINT MONO (-4300 1625);
DISPLAY INVISIBLE (-4300 1625);
FORCEPROP 2 LAST ROOM PVPP_KLM_VR
J 0
(-4950 1775);
PAINT GREEN (-4950 1775);
DISPLAY INVISIBLE (-4950 1775);
FORCEPROP 1 LAST SIZE 1B
J 0
(-4225 1650);
DISPLAY 0.893617 (-4225 1650);
PAINT GREEN (-4225 1650);
DISPLAY INVISIBLE (-4225 1650);
FORCEPROP 1 LAST VOLTAGE 0
J 0
(-4300 1700);
PAINT SKYBLUE (-4300 1700);
DISPLAY INVISIBLE (-4300 1700);
FORCEPROP 2 LAST BOM_COST PVPP_KLM_VR
J 0
(-5200 1775);
DISPLAY 1.042553 (-5200 1775);
PAINT WHITE (-5200 1775);
DISPLAY INVISIBLE (-5200 1775);
FORCEADD OFFPAGE..1
(-6925 3550);
FORCEPROP 2 LAST $XR0 105 
J 0
(-7177 3550);
DISPLAY 0.638298 (-7177 3550);
PAINT MONO (-7177 3550);
FORCEPROP 1 LAST COMMENT_BODY TRUE
J 0
(-6800 3450);
DISPLAY 0.872340 (-6800 3450);
PAINT GREEN (-6800 3450);
DISPLAY INVISIBLE (-6800 3450);
FORCEPROP 1 LAST OFFPAGE TRUE
J 0
(-6600 3425);
DISPLAY 0.872340 (-6600 3425);
PAINT GREEN (-6600 3425);
DISPLAY INVISIBLE (-6600 3425);
FORCEPROP 2 LAST PATH I21
J 0
(-7175 3600);
DISPLAY 1.021277 (-7175 3600);
PAINT ORANGE (-7175 3600);
DISPLAY INVISIBLE (-7175 3600);
FORCEPROP 2 LAST CDS_LIB mstr_standard
J 0
(-6925 3550);
PAINT MONO (-6925 3550);
DISPLAY INVISIBLE (-6925 3550);
FORCEADD OFFPAGE..1
(-6925 3775);
FORCEPROP 2 LAST $XR0 105 
J 0
(-7177 3775);
DISPLAY 0.638298 (-7177 3775);
PAINT MONO (-7177 3775);
FORCEPROP 1 LAST COMMENT_BODY TRUE
J 0
(-6800 3675);
DISPLAY 0.872340 (-6800 3675);
PAINT GREEN (-6800 3675);
DISPLAY INVISIBLE (-6800 3675);
FORCEPROP 1 LAST OFFPAGE TRUE
J 0
(-6600 3650);
DISPLAY 0.872340 (-6600 3650);
PAINT GREEN (-6600 3650);
DISPLAY INVISIBLE (-6600 3650);
FORCEPROP 2 LAST PATH I22
J 0
(-7175 3825);
DISPLAY 1.021277 (-7175 3825);
PAINT ORANGE (-7175 3825);
DISPLAY INVISIBLE (-7175 3825);
FORCEPROP 2 LAST CDS_LIB mstr_standard
J 0
(-6925 3775);
PAINT MONO (-6925 3775);
DISPLAY INVISIBLE (-6925 3775);
FORCEADD TAP..1
R 2
(-5925 3375);
FORCEPROP 3 LASTPIN (-5875 3375) SIG_NAME P3E_CPU0_PE2_SS_C_TXN<8>
J 0
(-5865 3385);
DISPLAY 0.659574 (-5865 3385);
PAINT MONO (-5865 3385);
DISPLAY INVISIBLE (-5865 3385);
FORCEPROP 1 LASTPIN (-5875 3375) BN 8
J 2
(-5863 3383);
DISPLAY 0.680851 (-5863 3383);
PAINT GREEN (-5863 3383);
FORCEPROP 1 LAST HDL_TAP TRUE
J 2
(-6250 3250);
DISPLAY 0.872340 (-6250 3250);
PAINT ORANGE (-6250 3250);
DISPLAY INVISIBLE (-6250 3250);
FORCEPROP 1 LAST BODY_TYPE PLUMBING
J 2
(-5925 3425);
DISPLAY 0.872340 (-5925 3425);
PAINT GREEN (-5925 3425);
DISPLAY INVISIBLE (-5925 3425);
FORCEPROP 1 LAST PATH I23
J 2
(-5923 3375);
DISPLAY 0.872340 (-5923 3375);
PAINT GREEN (-5923 3375);
DISPLAY INVISIBLE (-5923 3375);
FORCEPROP 2 LAST CDS_LIB mstr_standard
J 0
(-5925 3375);
PAINT MONO (-5925 3375);
DISPLAY INVISIBLE (-5925 3375);
FORCEADD TAP..1
R 2
(-5300 3425);
FORCEPROP 3 LASTPIN (-5250 3425) SIG_NAME P3E_CPU0_PE2_SS_C_TXP<8>
J 0
(-5240 3435);
DISPLAY 0.659574 (-5240 3435);
PAINT MONO (-5240 3435);
DISPLAY INVISIBLE (-5240 3435);
FORCEPROP 1 LASTPIN (-5250 3425) BN 8
J 2
(-5238 3433);
DISPLAY 0.680851 (-5238 3433);
PAINT GREEN (-5238 3433);
FORCEPROP 1 LAST HDL_TAP TRUE
J 2
(-5625 3300);
DISPLAY 0.872340 (-5625 3300);
PAINT ORANGE (-5625 3300);
DISPLAY INVISIBLE (-5625 3300);
FORCEPROP 1 LAST BODY_TYPE PLUMBING
J 2
(-5300 3475);
DISPLAY 0.872340 (-5300 3475);
PAINT GREEN (-5300 3475);
DISPLAY INVISIBLE (-5300 3475);
FORCEPROP 1 LAST PATH I24
J 2
(-5298 3425);
DISPLAY 0.872340 (-5298 3425);
PAINT GREEN (-5298 3425);
DISPLAY INVISIBLE (-5298 3425);
FORCEPROP 2 LAST CDS_LIB mstr_standard
J 0
(-5300 3425);
PAINT MONO (-5300 3425);
DISPLAY INVISIBLE (-5300 3425);
FORCEADD GND..1
(-4450 3575);
FORCEPROP 3 LASTPIN (-4450 3625) SIG_NAME GND\g
J 0
(-4440 3635);
DISPLAY 0.659574 (-4440 3635);
PAINT MONO (-4440 3635);
DISPLAY INVISIBLE (-4440 3635);
FORCEPROP 1 LAST HDL_POWER GND
J 0
(-4450 3800);
DISPLAY 0.893617 (-4450 3800);
PAINT GREEN (-4450 3800);
DISPLAY INVISIBLE (-4450 3800);
FORCEPROP 1 LAST BODY_TYPE PLUMBING
J 0
(-4495 3532);
DISPLAY 0.340426 (-4495 3532);
PAINT GREEN (-4495 3532);
DISPLAY INVISIBLE (-4495 3532);
FORCEPROP 1 LAST PATH I25
J 0
(-4375 3575);
DISPLAY 0.872340 (-4375 3575);
PAINT AQUA (-4375 3575);
DISPLAY INVISIBLE (-4375 3575);
FORCEPROP 2 LAST BOM_COST PVPP_KLM_VR
J 0
(-5350 3725);
DISPLAY 1.042553 (-5350 3725);
PAINT WHITE (-5350 3725);
DISPLAY INVISIBLE (-5350 3725);
FORCEPROP 1 LAST VOLTAGE 0
J 0
(-4450 3650);
PAINT SKYBLUE (-4450 3650);
DISPLAY INVISIBLE (-4450 3650);
FORCEPROP 1 LAST SIZE 1B
J 0
(-4375 3600);
DISPLAY 0.893617 (-4375 3600);
PAINT GREEN (-4375 3600);
DISPLAY INVISIBLE (-4375 3600);
FORCEPROP 2 LAST ROOM PVPP_KLM_VR
J 0
(-5100 3725);
PAINT GREEN (-5100 3725);
DISPLAY INVISIBLE (-5100 3725);
FORCEPROP 2 LAST CDS_LIB mstr_symbols
J 0
(-4450 3575);
PAINT MONO (-4450 3575);
DISPLAY INVISIBLE (-4450 3575);
FORCEADD GND..1
(-3700 1625);
FORCEPROP 3 LASTPIN (-3700 1675) SIG_NAME GND\g
J 0
(-3690 1685);
DISPLAY 0.659574 (-3690 1685);
PAINT MONO (-3690 1685);
DISPLAY INVISIBLE (-3690 1685);
FORCEPROP 1 LAST HDL_POWER GND
J 0
(-3700 1850);
DISPLAY 0.893617 (-3700 1850);
PAINT GREEN (-3700 1850);
DISPLAY INVISIBLE (-3700 1850);
FORCEPROP 1 LAST BODY_TYPE PLUMBING
J 0
(-3745 1582);
DISPLAY 0.340426 (-3745 1582);
PAINT GREEN (-3745 1582);
DISPLAY INVISIBLE (-3745 1582);
FORCEPROP 1 LAST PATH I26
J 0
(-3625 1625);
DISPLAY 0.872340 (-3625 1625);
PAINT AQUA (-3625 1625);
DISPLAY INVISIBLE (-3625 1625);
FORCEPROP 2 LAST CDS_LIB mstr_symbols
J 0
(-3700 1625);
PAINT MONO (-3700 1625);
DISPLAY INVISIBLE (-3700 1625);
FORCEPROP 2 LAST ROOM PVPP_KLM_VR
J 0
(-4350 1775);
PAINT GREEN (-4350 1775);
DISPLAY INVISIBLE (-4350 1775);
FORCEPROP 1 LAST SIZE 1B
J 0
(-3625 1650);
DISPLAY 0.893617 (-3625 1650);
PAINT GREEN (-3625 1650);
DISPLAY INVISIBLE (-3625 1650);
FORCEPROP 1 LAST VOLTAGE 0
J 0
(-3700 1700);
PAINT SKYBLUE (-3700 1700);
DISPLAY INVISIBLE (-3700 1700);
FORCEPROP 2 LAST BOM_COST PVPP_KLM_VR
J 0
(-4600 1775);
DISPLAY 1.042553 (-4600 1775);
PAINT WHITE (-4600 1775);
DISPLAY INVISIBLE (-4600 1775);
FORCEADD GND..1
(-3400 1625);
FORCEPROP 3 LASTPIN (-3400 1675) SIG_NAME GND\g
J 0
(-3390 1685);
DISPLAY 0.659574 (-3390 1685);
PAINT MONO (-3390 1685);
DISPLAY INVISIBLE (-3390 1685);
FORCEPROP 1 LAST HDL_POWER GND
J 0
(-3400 1850);
DISPLAY 0.893617 (-3400 1850);
PAINT GREEN (-3400 1850);
DISPLAY INVISIBLE (-3400 1850);
FORCEPROP 1 LAST BODY_TYPE PLUMBING
J 0
(-3445 1582);
DISPLAY 0.340426 (-3445 1582);
PAINT GREEN (-3445 1582);
DISPLAY INVISIBLE (-3445 1582);
FORCEPROP 1 LAST PATH I27
J 0
(-3325 1625);
DISPLAY 0.872340 (-3325 1625);
PAINT AQUA (-3325 1625);
DISPLAY INVISIBLE (-3325 1625);
FORCEPROP 2 LAST CDS_LIB mstr_symbols
J 0
(-3400 1625);
PAINT MONO (-3400 1625);
DISPLAY INVISIBLE (-3400 1625);
FORCEPROP 2 LAST ROOM PVPP_KLM_VR
J 0
(-4050 1775);
PAINT GREEN (-4050 1775);
DISPLAY INVISIBLE (-4050 1775);
FORCEPROP 1 LAST SIZE 1B
J 0
(-3325 1650);
DISPLAY 0.893617 (-3325 1650);
PAINT GREEN (-3325 1650);
DISPLAY INVISIBLE (-3325 1650);
FORCEPROP 1 LAST VOLTAGE 0
J 0
(-3400 1700);
PAINT SKYBLUE (-3400 1700);
DISPLAY INVISIBLE (-3400 1700);
FORCEPROP 2 LAST BOM_COST PVPP_KLM_VR
J 0
(-4300 1775);
DISPLAY 1.042553 (-4300 1775);
PAINT WHITE (-4300 1775);
DISPLAY INVISIBLE (-4300 1775);
FORCEADD OFFPAGE..4
(-2875 2125);
FORCEPROP 2 LAST $XR0 114 
J 0
(-2689 2125);
DISPLAY 0.638298 (-2689 2125);
PAINT MONO (-2689 2125);
FORCEPROP 1 LAST COMMENT_BODY TRUE
J 0
(-2900 2025);
DISPLAY 0.872340 (-2900 2025);
PAINT GREEN (-2900 2025);
DISPLAY INVISIBLE (-2900 2025);
FORCEPROP 1 LAST OFFPAGE TRUE
J 0
(-2550 2000);
DISPLAY 0.872340 (-2550 2000);
PAINT GREEN (-2550 2000);
DISPLAY INVISIBLE (-2550 2000);
FORCEPROP 2 LAST PATH I28
J 0
(-2675 2175);
DISPLAY 1.021277 (-2675 2175);
PAINT ORANGE (-2675 2175);
DISPLAY INVISIBLE (-2675 2175);
FORCEPROP 2 LAST CDS_LIB mstr_standard
J 0
(-2875 2125);
PAINT MONO (-2875 2125);
DISPLAY INVISIBLE (-2875 2125);
FORCEADD TAP..6
R 2
(-2500 2325);
FORCEPROP 3 LASTPIN (-2550 2325) SIG_NAME P3E_CPU0_PE2_SS_RXN<15>
J 0
(-2540 2335);
DISPLAY 0.659574 (-2540 2335);
PAINT MONO (-2540 2335);
DISPLAY INVISIBLE (-2540 2335);
FORCEPROP 1 LASTPIN (-2550 2325) BN 15
J 2
(-2498 2333);
DISPLAY 0.680851 (-2498 2333);
PAINT GREEN (-2498 2333);
FORCEPROP 1 LAST HDL_TAP TRUE
J 2
(-2825 2200);
DISPLAY 0.872340 (-2825 2200);
PAINT ORANGE (-2825 2200);
DISPLAY INVISIBLE (-2825 2200);
FORCEPROP 1 LAST BODY_TYPE PLUMBING
J 2
(-2500 2275);
DISPLAY 0.872340 (-2500 2275);
PAINT GREEN (-2500 2275);
DISPLAY INVISIBLE (-2500 2275);
FORCEPROP 1 LAST PATH I29
J 2
(-2498 2325);
DISPLAY 0.872340 (-2498 2325);
PAINT GREEN (-2498 2325);
DISPLAY INVISIBLE (-2498 2325);
FORCEPROP 2 LAST CDS_LIB mstr_standard
J 0
(-2500 2325);
PAINT MONO (-2500 2325);
DISPLAY INVISIBLE (-2500 2325);
FORCEADD OFFPAGE..1
(-5500 2175);
FORCEPROP 2 LAST $XR0 114 
J 0
(-5752 2175);
DISPLAY 0.638298 (-5752 2175);
PAINT MONO (-5752 2175);
FORCEPROP 1 LAST COMMENT_BODY TRUE
J 0
(-5375 2075);
DISPLAY 0.872340 (-5375 2075);
PAINT PEACH (-5375 2075);
DISPLAY INVISIBLE (-5375 2075);
FORCEPROP 1 LAST OFFPAGE TRUE
J 0
(-5175 2050);
DISPLAY 0.872340 (-5175 2050);
PAINT GREEN (-5175 2050);
DISPLAY INVISIBLE (-5175 2050);
FORCEPROP 2 LAST PATH I3
J 0
(-5750 2225);
DISPLAY 1.021277 (-5750 2225);
PAINT ORANGE (-5750 2225);
DISPLAY INVISIBLE (-5750 2225);
FORCEPROP 2 LAST CDS_LIB mstr_standard
J 0
(-5500 2175);
PAINT MONO (-5500 2175);
DISPLAY INVISIBLE (-5500 2175);
FORCEADD TAP..6
R 2
(-2300 2275);
FORCEPROP 3 LASTPIN (-2350 2275) SIG_NAME P3E_CPU0_PE2_SS_RXP<15>
J 0
(-2340 2285);
DISPLAY 0.659574 (-2340 2285);
PAINT MONO (-2340 2285);
DISPLAY INVISIBLE (-2340 2285);
FORCEPROP 1 LASTPIN (-2350 2275) BN 15
J 2
(-2298 2283);
DISPLAY 0.680851 (-2298 2283);
PAINT GREEN (-2298 2283);
FORCEPROP 1 LAST HDL_TAP TRUE
J 2
(-2625 2150);
DISPLAY 0.872340 (-2625 2150);
PAINT ORANGE (-2625 2150);
DISPLAY INVISIBLE (-2625 2150);
FORCEPROP 1 LAST BODY_TYPE PLUMBING
J 2
(-2300 2225);
DISPLAY 0.872340 (-2300 2225);
PAINT GREEN (-2300 2225);
DISPLAY INVISIBLE (-2300 2225);
FORCEPROP 1 LAST PATH I30
J 2
(-2298 2275);
DISPLAY 0.872340 (-2298 2275);
PAINT GREEN (-2298 2275);
DISPLAY INVISIBLE (-2298 2275);
FORCEPROP 2 LAST CDS_LIB mstr_standard
J 0
(-2300 2275);
PAINT MONO (-2300 2275);
DISPLAY INVISIBLE (-2300 2275);
FORCEADD TAP..6
R 2
(-2500 2575);
FORCEPROP 3 LASTPIN (-2550 2575) SIG_NAME P3E_CPU0_PE2_SS_RXN<13>
J 0
(-2540 2585);
DISPLAY 0.659574 (-2540 2585);
PAINT MONO (-2540 2585);
DISPLAY INVISIBLE (-2540 2585);
FORCEPROP 1 LASTPIN (-2550 2575) BN 13
J 2
(-2498 2583);
DISPLAY 0.680851 (-2498 2583);
PAINT GREEN (-2498 2583);
FORCEPROP 1 LAST HDL_TAP TRUE
J 2
(-2825 2450);
DISPLAY 0.872340 (-2825 2450);
PAINT ORANGE (-2825 2450);
DISPLAY INVISIBLE (-2825 2450);
FORCEPROP 1 LAST BODY_TYPE PLUMBING
J 2
(-2500 2525);
DISPLAY 0.872340 (-2500 2525);
PAINT GREEN (-2500 2525);
DISPLAY INVISIBLE (-2500 2525);
FORCEPROP 1 LAST PATH I31
J 2
(-2498 2575);
DISPLAY 0.872340 (-2498 2575);
PAINT GREEN (-2498 2575);
DISPLAY INVISIBLE (-2498 2575);
FORCEPROP 2 LAST CDS_LIB mstr_standard
J 0
(-2500 2575);
PAINT MONO (-2500 2575);
DISPLAY INVISIBLE (-2500 2575);
FORCEADD TAP..6
R 2
(-2500 2475);
FORCEPROP 3 LASTPIN (-2550 2475) SIG_NAME P3E_CPU0_PE2_SS_RXN<14>
J 0
(-2540 2485);
DISPLAY 0.659574 (-2540 2485);
PAINT MONO (-2540 2485);
DISPLAY INVISIBLE (-2540 2485);
FORCEPROP 1 LASTPIN (-2550 2475) BN 14
J 2
(-2498 2483);
DISPLAY 0.680851 (-2498 2483);
PAINT GREEN (-2498 2483);
FORCEPROP 1 LAST HDL_TAP TRUE
J 2
(-2825 2350);
DISPLAY 0.872340 (-2825 2350);
PAINT ORANGE (-2825 2350);
DISPLAY INVISIBLE (-2825 2350);
FORCEPROP 1 LAST BODY_TYPE PLUMBING
J 2
(-2500 2425);
DISPLAY 0.872340 (-2500 2425);
PAINT GREEN (-2500 2425);
DISPLAY INVISIBLE (-2500 2425);
FORCEPROP 1 LAST PATH I32
J 2
(-2498 2475);
DISPLAY 0.872340 (-2498 2475);
PAINT GREEN (-2498 2475);
DISPLAY INVISIBLE (-2498 2475);
FORCEPROP 2 LAST CDS_LIB mstr_standard
J 0
(-2500 2475);
PAINT MONO (-2500 2475);
DISPLAY INVISIBLE (-2500 2475);
FORCEADD TAP..6
R 2
(-2500 2775);
FORCEPROP 3 LASTPIN (-2550 2775) SIG_NAME P3E_CPU0_PE2_SS_RXN<12>
J 0
(-2540 2785);
DISPLAY 0.659574 (-2540 2785);
PAINT MONO (-2540 2785);
DISPLAY INVISIBLE (-2540 2785);
FORCEPROP 1 LASTPIN (-2550 2775) BN 12
J 2
(-2498 2783);
DISPLAY 0.680851 (-2498 2783);
PAINT GREEN (-2498 2783);
FORCEPROP 1 LAST HDL_TAP TRUE
J 2
(-2825 2650);
DISPLAY 0.872340 (-2825 2650);
PAINT ORANGE (-2825 2650);
DISPLAY INVISIBLE (-2825 2650);
FORCEPROP 1 LAST BODY_TYPE PLUMBING
J 2
(-2500 2725);
DISPLAY 0.872340 (-2500 2725);
PAINT GREEN (-2500 2725);
DISPLAY INVISIBLE (-2500 2725);
FORCEPROP 1 LAST PATH I33
J 2
(-2498 2775);
DISPLAY 0.872340 (-2498 2775);
PAINT GREEN (-2498 2775);
DISPLAY INVISIBLE (-2498 2775);
FORCEPROP 2 LAST CDS_LIB mstr_standard
J 0
(-2500 2775);
PAINT MONO (-2500 2775);
DISPLAY INVISIBLE (-2500 2775);
FORCEADD TAP..6
R 2
(-2500 2925);
FORCEPROP 3 LASTPIN (-2550 2925) SIG_NAME P3E_CPU0_PE2_SS_RXN<11>
J 0
(-2540 2935);
DISPLAY 0.659574 (-2540 2935);
PAINT MONO (-2540 2935);
DISPLAY INVISIBLE (-2540 2935);
FORCEPROP 1 LASTPIN (-2550 2925) BN 11
J 2
(-2498 2933);
DISPLAY 0.680851 (-2498 2933);
PAINT GREEN (-2498 2933);
FORCEPROP 1 LAST HDL_TAP TRUE
J 2
(-2825 2800);
DISPLAY 0.872340 (-2825 2800);
PAINT ORANGE (-2825 2800);
DISPLAY INVISIBLE (-2825 2800);
FORCEPROP 1 LAST BODY_TYPE PLUMBING
J 2
(-2500 2875);
DISPLAY 0.872340 (-2500 2875);
PAINT GREEN (-2500 2875);
DISPLAY INVISIBLE (-2500 2875);
FORCEPROP 1 LAST PATH I34
J 2
(-2498 2925);
DISPLAY 0.872340 (-2498 2925);
PAINT GREEN (-2498 2925);
DISPLAY INVISIBLE (-2498 2925);
FORCEPROP 2 LAST CDS_LIB mstr_standard
J 0
(-2500 2925);
PAINT MONO (-2500 2925);
DISPLAY INVISIBLE (-2500 2925);
FORCEADD TAP..6
R 2
(-2500 3075);
FORCEPROP 3 LASTPIN (-2550 3075) SIG_NAME P3E_CPU0_PE2_SS_RXN<10>
J 0
(-2540 3085);
DISPLAY 0.659574 (-2540 3085);
PAINT MONO (-2540 3085);
DISPLAY INVISIBLE (-2540 3085);
FORCEPROP 1 LASTPIN (-2550 3075) BN 10
J 2
(-2498 3083);
DISPLAY 0.680851 (-2498 3083);
PAINT GREEN (-2498 3083);
FORCEPROP 1 LAST HDL_TAP TRUE
J 2
(-2825 2950);
DISPLAY 0.872340 (-2825 2950);
PAINT ORANGE (-2825 2950);
DISPLAY INVISIBLE (-2825 2950);
FORCEPROP 1 LAST BODY_TYPE PLUMBING
J 2
(-2500 3025);
DISPLAY 0.872340 (-2500 3025);
PAINT GREEN (-2500 3025);
DISPLAY INVISIBLE (-2500 3025);
FORCEPROP 1 LAST PATH I35
J 2
(-2498 3075);
DISPLAY 0.872340 (-2498 3075);
PAINT GREEN (-2498 3075);
DISPLAY INVISIBLE (-2498 3075);
FORCEPROP 2 LAST CDS_LIB mstr_standard
J 0
(-2500 3075);
PAINT MONO (-2500 3075);
DISPLAY INVISIBLE (-2500 3075);
FORCEADD TAP..6
R 2
(-2500 3225);
FORCEPROP 3 LASTPIN (-2550 3225) SIG_NAME P3E_CPU0_PE2_SS_RXN<9>
J 0
(-2540 3235);
DISPLAY 0.659574 (-2540 3235);
PAINT MONO (-2540 3235);
DISPLAY INVISIBLE (-2540 3235);
FORCEPROP 1 LASTPIN (-2550 3225) BN 9
J 2
(-2498 3233);
DISPLAY 0.680851 (-2498 3233);
PAINT GREEN (-2498 3233);
FORCEPROP 1 LAST HDL_TAP TRUE
J 2
(-2825 3100);
DISPLAY 0.872340 (-2825 3100);
PAINT ORANGE (-2825 3100);
DISPLAY INVISIBLE (-2825 3100);
FORCEPROP 1 LAST BODY_TYPE PLUMBING
J 2
(-2500 3175);
DISPLAY 0.872340 (-2500 3175);
PAINT GREEN (-2500 3175);
DISPLAY INVISIBLE (-2500 3175);
FORCEPROP 1 LAST PATH I36
J 2
(-2498 3225);
DISPLAY 0.872340 (-2498 3225);
PAINT GREEN (-2498 3225);
DISPLAY INVISIBLE (-2498 3225);
FORCEPROP 2 LAST CDS_LIB mstr_standard
J 0
(-2500 3225);
PAINT MONO (-2500 3225);
DISPLAY INVISIBLE (-2500 3225);
FORCEADD TAP..6
R 2
(-2300 2425);
FORCEPROP 3 LASTPIN (-2350 2425) SIG_NAME P3E_CPU0_PE2_SS_RXP<14>
J 0
(-2340 2435);
DISPLAY 0.659574 (-2340 2435);
PAINT MONO (-2340 2435);
DISPLAY INVISIBLE (-2340 2435);
FORCEPROP 1 LASTPIN (-2350 2425) BN 14
J 2
(-2298 2433);
DISPLAY 0.680851 (-2298 2433);
PAINT GREEN (-2298 2433);
FORCEPROP 1 LAST HDL_TAP TRUE
J 2
(-2625 2300);
DISPLAY 0.872340 (-2625 2300);
PAINT ORANGE (-2625 2300);
DISPLAY INVISIBLE (-2625 2300);
FORCEPROP 1 LAST BODY_TYPE PLUMBING
J 2
(-2300 2375);
DISPLAY 0.872340 (-2300 2375);
PAINT GREEN (-2300 2375);
DISPLAY INVISIBLE (-2300 2375);
FORCEPROP 1 LAST PATH I37
J 2
(-2298 2425);
DISPLAY 0.872340 (-2298 2425);
PAINT GREEN (-2298 2425);
DISPLAY INVISIBLE (-2298 2425);
FORCEPROP 2 LAST CDS_LIB mstr_standard
J 0
(-2300 2425);
PAINT MONO (-2300 2425);
DISPLAY INVISIBLE (-2300 2425);
FORCEADD TAP..6
R 2
(-2300 2725);
FORCEPROP 3 LASTPIN (-2350 2725) SIG_NAME P3E_CPU0_PE2_SS_RXP<12>
J 0
(-2340 2735);
DISPLAY 0.659574 (-2340 2735);
PAINT MONO (-2340 2735);
DISPLAY INVISIBLE (-2340 2735);
FORCEPROP 1 LASTPIN (-2350 2725) BN 12
J 2
(-2298 2733);
DISPLAY 0.680851 (-2298 2733);
PAINT GREEN (-2298 2733);
FORCEPROP 1 LAST HDL_TAP TRUE
J 2
(-2625 2600);
DISPLAY 0.872340 (-2625 2600);
PAINT ORANGE (-2625 2600);
DISPLAY INVISIBLE (-2625 2600);
FORCEPROP 1 LAST BODY_TYPE PLUMBING
J 2
(-2300 2675);
DISPLAY 0.872340 (-2300 2675);
PAINT GREEN (-2300 2675);
DISPLAY INVISIBLE (-2300 2675);
FORCEPROP 1 LAST PATH I38
J 2
(-2298 2725);
DISPLAY 0.872340 (-2298 2725);
PAINT GREEN (-2298 2725);
DISPLAY INVISIBLE (-2298 2725);
FORCEPROP 2 LAST CDS_LIB mstr_standard
J 0
(-2300 2725);
PAINT MONO (-2300 2725);
DISPLAY INVISIBLE (-2300 2725);
FORCEADD TAP..6
R 2
(-2300 2625);
FORCEPROP 3 LASTPIN (-2350 2625) SIG_NAME P3E_CPU0_PE2_SS_RXP<13>
J 0
(-2340 2635);
DISPLAY 0.659574 (-2340 2635);
PAINT MONO (-2340 2635);
DISPLAY INVISIBLE (-2340 2635);
FORCEPROP 1 LASTPIN (-2350 2625) BN 13
J 2
(-2298 2633);
DISPLAY 0.680851 (-2298 2633);
PAINT GREEN (-2298 2633);
FORCEPROP 1 LAST HDL_TAP TRUE
J 2
(-2625 2500);
DISPLAY 0.872340 (-2625 2500);
PAINT ORANGE (-2625 2500);
DISPLAY INVISIBLE (-2625 2500);
FORCEPROP 1 LAST BODY_TYPE PLUMBING
J 2
(-2300 2575);
DISPLAY 0.872340 (-2300 2575);
PAINT GREEN (-2300 2575);
DISPLAY INVISIBLE (-2300 2575);
FORCEPROP 1 LAST PATH I39
J 2
(-2298 2625);
DISPLAY 0.872340 (-2298 2625);
PAINT GREEN (-2298 2625);
DISPLAY INVISIBLE (-2298 2625);
FORCEPROP 2 LAST CDS_LIB mstr_standard
J 0
(-2300 2625);
PAINT MONO (-2300 2625);
DISPLAY INVISIBLE (-2300 2625);
FORCEADD OFFPAGE..1
(-5500 2225);
FORCEPROP 2 LAST $XR0 114 
J 0
(-5752 2225);
DISPLAY 0.638298 (-5752 2225);
PAINT MONO (-5752 2225);
FORCEPROP 1 LAST COMMENT_BODY TRUE
J 0
(-5375 2125);
DISPLAY 0.872340 (-5375 2125);
PAINT PEACH (-5375 2125);
DISPLAY INVISIBLE (-5375 2125);
FORCEPROP 1 LAST OFFPAGE TRUE
J 0
(-5175 2100);
DISPLAY 0.872340 (-5175 2100);
PAINT GREEN (-5175 2100);
DISPLAY INVISIBLE (-5175 2100);
FORCEPROP 2 LAST PATH I4
J 0
(-5750 2275);
DISPLAY 1.021277 (-5750 2275);
PAINT ORANGE (-5750 2275);
DISPLAY INVISIBLE (-5750 2275);
FORCEPROP 2 LAST CDS_LIB mstr_standard
J 0
(-5500 2225);
PAINT MONO (-5500 2225);
DISPLAY INVISIBLE (-5500 2225);
FORCEADD TAP..6
R 2
(-2300 3025);
FORCEPROP 3 LASTPIN (-2350 3025) SIG_NAME P3E_CPU0_PE2_SS_RXP<10>
J 0
(-2340 3035);
DISPLAY 0.659574 (-2340 3035);
PAINT MONO (-2340 3035);
DISPLAY INVISIBLE (-2340 3035);
FORCEPROP 1 LASTPIN (-2350 3025) BN 10
J 2
(-2298 3033);
DISPLAY 0.680851 (-2298 3033);
PAINT GREEN (-2298 3033);
FORCEPROP 1 LAST HDL_TAP TRUE
J 2
(-2625 2900);
DISPLAY 0.872340 (-2625 2900);
PAINT ORANGE (-2625 2900);
DISPLAY INVISIBLE (-2625 2900);
FORCEPROP 1 LAST BODY_TYPE PLUMBING
J 2
(-2300 2975);
DISPLAY 0.872340 (-2300 2975);
PAINT GREEN (-2300 2975);
DISPLAY INVISIBLE (-2300 2975);
FORCEPROP 1 LAST PATH I40
J 2
(-2298 3025);
DISPLAY 0.872340 (-2298 3025);
PAINT GREEN (-2298 3025);
DISPLAY INVISIBLE (-2298 3025);
FORCEPROP 2 LAST CDS_LIB mstr_standard
J 0
(-2300 3025);
PAINT MONO (-2300 3025);
DISPLAY INVISIBLE (-2300 3025);
FORCEADD TAP..6
R 2
(-2300 2875);
FORCEPROP 3 LASTPIN (-2350 2875) SIG_NAME P3E_CPU0_PE2_SS_RXP<11>
J 0
(-2340 2885);
DISPLAY 0.659574 (-2340 2885);
PAINT MONO (-2340 2885);
DISPLAY INVISIBLE (-2340 2885);
FORCEPROP 1 LASTPIN (-2350 2875) BN 11
J 2
(-2298 2883);
DISPLAY 0.680851 (-2298 2883);
PAINT GREEN (-2298 2883);
FORCEPROP 1 LAST HDL_TAP TRUE
J 2
(-2625 2750);
DISPLAY 0.872340 (-2625 2750);
PAINT ORANGE (-2625 2750);
DISPLAY INVISIBLE (-2625 2750);
FORCEPROP 1 LAST BODY_TYPE PLUMBING
J 2
(-2300 2825);
DISPLAY 0.872340 (-2300 2825);
PAINT GREEN (-2300 2825);
DISPLAY INVISIBLE (-2300 2825);
FORCEPROP 1 LAST PATH I41
J 2
(-2298 2875);
DISPLAY 0.872340 (-2298 2875);
PAINT GREEN (-2298 2875);
DISPLAY INVISIBLE (-2298 2875);
FORCEPROP 2 LAST CDS_LIB mstr_standard
J 0
(-2300 2875);
PAINT MONO (-2300 2875);
DISPLAY INVISIBLE (-2300 2875);
FORCEADD TAP..6
R 2
(-2300 3175);
FORCEPROP 3 LASTPIN (-2350 3175) SIG_NAME P3E_CPU0_PE2_SS_RXP<9>
J 0
(-2340 3185);
DISPLAY 0.659574 (-2340 3185);
PAINT MONO (-2340 3185);
DISPLAY INVISIBLE (-2340 3185);
FORCEPROP 1 LASTPIN (-2350 3175) BN 9
J 2
(-2298 3183);
DISPLAY 0.680851 (-2298 3183);
PAINT GREEN (-2298 3183);
FORCEPROP 1 LAST HDL_TAP TRUE
J 2
(-2625 3050);
DISPLAY 0.872340 (-2625 3050);
PAINT ORANGE (-2625 3050);
DISPLAY INVISIBLE (-2625 3050);
FORCEPROP 1 LAST BODY_TYPE PLUMBING
J 2
(-2300 3125);
DISPLAY 0.872340 (-2300 3125);
PAINT GREEN (-2300 3125);
DISPLAY INVISIBLE (-2300 3125);
FORCEPROP 1 LAST PATH I42
J 2
(-2298 3175);
DISPLAY 0.872340 (-2298 3175);
PAINT GREEN (-2298 3175);
DISPLAY INVISIBLE (-2298 3175);
FORCEPROP 2 LAST CDS_LIB mstr_standard
J 0
(-2300 3175);
PAINT MONO (-2300 3175);
DISPLAY INVISIBLE (-2300 3175);
FORCEADD TAP..6
R 2
(-2300 3325);
FORCEPROP 3 LASTPIN (-2350 3325) SIG_NAME P3E_CPU0_PE2_SS_RXP<8>
J 0
(-2340 3335);
DISPLAY 0.659574 (-2340 3335);
PAINT MONO (-2340 3335);
DISPLAY INVISIBLE (-2340 3335);
FORCEPROP 1 LASTPIN (-2350 3325) BN 8
J 2
(-2298 3333);
DISPLAY 0.680851 (-2298 3333);
PAINT GREEN (-2298 3333);
FORCEPROP 1 LAST HDL_TAP TRUE
J 2
(-2625 3200);
DISPLAY 0.872340 (-2625 3200);
PAINT ORANGE (-2625 3200);
DISPLAY INVISIBLE (-2625 3200);
FORCEPROP 1 LAST BODY_TYPE PLUMBING
J 2
(-2300 3275);
DISPLAY 0.872340 (-2300 3275);
PAINT GREEN (-2300 3275);
DISPLAY INVISIBLE (-2300 3275);
FORCEPROP 1 LAST PATH I43
J 2
(-2298 3325);
DISPLAY 0.872340 (-2298 3325);
PAINT GREEN (-2298 3325);
DISPLAY INVISIBLE (-2298 3325);
FORCEPROP 2 LAST CDS_LIB mstr_standard
J 0
(-2300 3325);
PAINT MONO (-2300 3325);
DISPLAY INVISIBLE (-2300 3325);
FORCEADD TAP..6
R 2
(-2500 3375);
FORCEPROP 3 LASTPIN (-2550 3375) SIG_NAME P3E_CPU0_PE2_SS_RXN<8>
J 0
(-2540 3385);
DISPLAY 0.659574 (-2540 3385);
PAINT MONO (-2540 3385);
DISPLAY INVISIBLE (-2540 3385);
FORCEPROP 1 LASTPIN (-2550 3375) BN 8
J 2
(-2498 3383);
DISPLAY 0.680851 (-2498 3383);
PAINT GREEN (-2498 3383);
FORCEPROP 1 LAST HDL_TAP TRUE
J 2
(-2825 3250);
DISPLAY 0.872340 (-2825 3250);
PAINT ORANGE (-2825 3250);
DISPLAY INVISIBLE (-2825 3250);
FORCEPROP 1 LAST BODY_TYPE PLUMBING
J 2
(-2500 3325);
DISPLAY 0.872340 (-2500 3325);
PAINT GREEN (-2500 3325);
DISPLAY INVISIBLE (-2500 3325);
FORCEPROP 1 LAST PATH I44
J 2
(-2498 3375);
DISPLAY 0.872340 (-2498 3375);
PAINT GREEN (-2498 3375);
DISPLAY INVISIBLE (-2498 3375);
FORCEPROP 2 LAST CDS_LIB mstr_standard
J 0
(-2500 3375);
PAINT MONO (-2500 3375);
DISPLAY INVISIBLE (-2500 3375);
FORCEADD OFFPAGE..2
(-1275 3600);
FORCEPROP 2 LAST $XR1 ?
J 0
(-1081 3600);
DISPLAY 0.638298 (-1081 3600);
PAINT MONO (-1081 3600);
FORCEPROP 2 LAST $XR0 31 
J 0
(-981 3600);
DISPLAY 0.638298 (-981 3600);
PAINT MONO (-981 3600);
FORCEPROP 1 LAST COMMENT_BODY TRUE
J 0
(-1320 3505);
DISPLAY 0.872340 (-1320 3505);
PAINT GREEN (-1320 3505);
DISPLAY INVISIBLE (-1320 3505);
FORCEPROP 1 LAST OFFPAGE TRUE
J 0
(-950 3475);
DISPLAY 0.872340 (-950 3475);
PAINT ORANGE (-950 3475);
DISPLAY INVISIBLE (-950 3475);
FORCEPROP 2 LAST PATH I45
J 0
(-975 3650);
DISPLAY 1.021277 (-975 3650);
PAINT ORANGE (-975 3650);
DISPLAY INVISIBLE (-975 3650);
FORCEPROP 2 LAST CDS_LIB mstr_standard
J 0
(-1275 3600);
PAINT MONO (-1275 3600);
DISPLAY INVISIBLE (-1275 3600);
FORCEADD OFFPAGE..2
(-1275 3475);
FORCEPROP 2 LAST $XR1 ?
J 0
(-1046 3475);
DISPLAY 0.638298 (-1046 3475);
PAINT MONO (-1046 3475);
FORCEPROP 2 LAST $XR0 31 
J 0
(-971 3475);
DISPLAY 0.638298 (-971 3475);
PAINT MONO (-971 3475);
FORCEPROP 1 LAST COMMENT_BODY TRUE
J 0
(-1320 3380);
DISPLAY 0.872340 (-1320 3380);
PAINT GREEN (-1320 3380);
DISPLAY INVISIBLE (-1320 3380);
FORCEPROP 1 LAST OFFPAGE TRUE
J 0
(-950 3350);
DISPLAY 0.872340 (-950 3350);
PAINT ORANGE (-950 3350);
DISPLAY INVISIBLE (-950 3350);
FORCEPROP 2 LAST PATH I46
J 0
(-950 3525);
DISPLAY 1.021277 (-950 3525);
PAINT ORANGE (-950 3525);
DISPLAY INVISIBLE (-950 3525);
FORCEPROP 2 LAST CDS_LIB mstr_standard
J 0
(-1275 3475);
PAINT MONO (-1275 3475);
DISPLAY INVISIBLE (-1275 3475);
FORCEADD OFFPAGE..4
(-2875 2175);
FORCEPROP 2 LAST $XR0 114 
J 0
(-2689 2175);
DISPLAY 0.638298 (-2689 2175);
PAINT MONO (-2689 2175);
FORCEPROP 1 LAST COMMENT_BODY TRUE
J 0
(-2900 2075);
DISPLAY 0.872340 (-2900 2075);
PAINT GREEN (-2900 2075);
DISPLAY INVISIBLE (-2900 2075);
FORCEPROP 1 LAST OFFPAGE TRUE
J 0
(-2550 2050);
DISPLAY 0.872340 (-2550 2050);
PAINT GREEN (-2550 2050);
DISPLAY INVISIBLE (-2550 2050);
FORCEPROP 2 LAST PATH I47
J 0
(-2675 2225);
DISPLAY 1.021277 (-2675 2225);
PAINT ORANGE (-2675 2225);
DISPLAY INVISIBLE (-2675 2225);
FORCEPROP 2 LAST CDS_LIB mstr_standard
J 0
(-2875 2175);
PAINT MONO (-2875 2175);
DISPLAY INVISIBLE (-2875 2175);
FORCEADD SMC-CONN60A-22-GP..1
(-4025 2775);
FORCEPROP 0 LASTPIN (-4275 1925) $PN PTH2
J 2
(-4285 1935);
DISPLAY 0.808511 (-4285 1935);
PAINT MONO (-4285 1935);
FORCEPROP 1 LAST VALUE SMC-CONN60A-22-GP
J 0
(-4125 1825);
DISPLAY 0.617021 (-4125 1825);
PAINT GREEN (-4125 1825);
FORCEPROP 0 LASTPIN (-4275 3625) $PN PTH1
J 2
(-4285 3635);
DISPLAY 0.808511 (-4285 3635);
PAINT MONO (-4285 3635);
FORCEPROP 0 LASTPIN (-3875 1975) $PN NP2
J 0
(-3865 1985);
DISPLAY 0.808511 (-3865 1985);
PAINT MONO (-3865 1985);
FORCEPROP 0 LASTPIN (-4175 3575) $PN NP1
J 2
(-4185 3585);
DISPLAY 0.808511 (-4185 3585);
PAINT MONO (-4185 3585);
FORCEPROP 0 LASTPIN (-3775 2025) $PN 60
J 0
(-3765 2035);
DISPLAY 0.808511 (-3765 2035);
PAINT MONO (-3765 2035);
FORCEPROP 0 LASTPIN (-3775 2075) $PN 58
J 0
(-3765 2085);
DISPLAY 0.808511 (-3765 2085);
PAINT MONO (-3765 2085);
FORCEPROP 0 LASTPIN (-3775 2125) $PN 56
J 0
(-3765 2135);
DISPLAY 0.808511 (-3765 2135);
PAINT MONO (-3765 2135);
FORCEPROP 0 LASTPIN (-3775 2175) $PN 54
J 0
(-3765 2185);
DISPLAY 0.808511 (-3765 2185);
PAINT MONO (-3765 2185);
FORCEPROP 0 LASTPIN (-3775 2225) $PN 52
J 0
(-3765 2235);
DISPLAY 0.808511 (-3765 2235);
PAINT MONO (-3765 2235);
FORCEPROP 0 LASTPIN (-3775 2275) $PN 50
J 0
(-3765 2285);
DISPLAY 0.808511 (-3765 2285);
PAINT MONO (-3765 2285);
FORCEPROP 0 LASTPIN (-3775 2325) $PN 48
J 0
(-3765 2335);
DISPLAY 0.808511 (-3765 2335);
PAINT MONO (-3765 2335);
FORCEPROP 0 LASTPIN (-3775 2375) $PN 46
J 0
(-3765 2385);
DISPLAY 0.808511 (-3765 2385);
PAINT MONO (-3765 2385);
FORCEPROP 0 LASTPIN (-3775 2425) $PN 44
J 0
(-3765 2435);
DISPLAY 0.808511 (-3765 2435);
PAINT MONO (-3765 2435);
FORCEPROP 0 LASTPIN (-3775 2475) $PN 42
J 0
(-3765 2485);
DISPLAY 0.808511 (-3765 2485);
PAINT MONO (-3765 2485);
FORCEPROP 0 LASTPIN (-3775 2525) $PN 40
J 0
(-3765 2535);
DISPLAY 0.808511 (-3765 2535);
PAINT MONO (-3765 2535);
FORCEPROP 0 LASTPIN (-3775 2575) $PN 38
J 0
(-3765 2585);
DISPLAY 0.808511 (-3765 2585);
PAINT MONO (-3765 2585);
FORCEPROP 0 LASTPIN (-3775 2625) $PN 36
J 0
(-3765 2635);
DISPLAY 0.808511 (-3765 2635);
PAINT MONO (-3765 2635);
FORCEPROP 0 LASTPIN (-3775 2675) $PN 34
J 0
(-3765 2685);
DISPLAY 0.808511 (-3765 2685);
PAINT MONO (-3765 2685);
FORCEPROP 0 LASTPIN (-3775 2725) $PN 32
J 0
(-3765 2735);
DISPLAY 0.808511 (-3765 2735);
PAINT MONO (-3765 2735);
FORCEPROP 0 LASTPIN (-3775 2775) $PN 30
J 0
(-3765 2785);
DISPLAY 0.808511 (-3765 2785);
PAINT MONO (-3765 2785);
FORCEPROP 0 LASTPIN (-3775 2825) $PN 28
J 0
(-3765 2835);
DISPLAY 0.808511 (-3765 2835);
PAINT MONO (-3765 2835);
FORCEPROP 0 LASTPIN (-3775 2875) $PN 26
J 0
(-3765 2885);
DISPLAY 0.808511 (-3765 2885);
PAINT MONO (-3765 2885);
FORCEPROP 0 LASTPIN (-3775 2925) $PN 24
J 0
(-3765 2935);
DISPLAY 0.808511 (-3765 2935);
PAINT MONO (-3765 2935);
FORCEPROP 0 LASTPIN (-3775 2975) $PN 22
J 0
(-3765 2985);
DISPLAY 0.808511 (-3765 2985);
PAINT MONO (-3765 2985);
FORCEPROP 0 LASTPIN (-3775 3025) $PN 20
J 0
(-3765 3035);
DISPLAY 0.808511 (-3765 3035);
PAINT MONO (-3765 3035);
FORCEPROP 0 LASTPIN (-3775 3075) $PN 18
J 0
(-3765 3085);
DISPLAY 0.808511 (-3765 3085);
PAINT MONO (-3765 3085);
FORCEPROP 0 LASTPIN (-3775 3125) $PN 16
J 0
(-3765 3135);
DISPLAY 0.808511 (-3765 3135);
PAINT MONO (-3765 3135);
FORCEPROP 0 LASTPIN (-3775 3175) $PN 14
J 0
(-3765 3185);
DISPLAY 0.808511 (-3765 3185);
PAINT MONO (-3765 3185);
FORCEPROP 0 LASTPIN (-3775 3225) $PN 12
J 0
(-3765 3235);
DISPLAY 0.808511 (-3765 3235);
PAINT MONO (-3765 3235);
FORCEPROP 0 LASTPIN (-3775 3275) $PN 10
J 0
(-3765 3285);
DISPLAY 0.808511 (-3765 3285);
PAINT MONO (-3765 3285);
FORCEPROP 0 LASTPIN (-4275 2075) $PN 57
J 2
(-4285 2085);
DISPLAY 0.808511 (-4285 2085);
PAINT MONO (-4285 2085);
FORCEPROP 0 LASTPIN (-4275 2225) $PN 51
J 2
(-4285 2235);
DISPLAY 0.808511 (-4285 2235);
PAINT MONO (-4285 2235);
FORCEPROP 0 LASTPIN (-4275 2275) $PN 49
J 2
(-4285 2285);
DISPLAY 0.808511 (-4285 2285);
PAINT MONO (-4285 2285);
FORCEPROP 0 LASTPIN (-4275 2325) $PN 47
J 2
(-4285 2335);
DISPLAY 0.808511 (-4285 2335);
PAINT MONO (-4285 2335);
FORCEPROP 0 LASTPIN (-4275 2375) $PN 45
J 2
(-4285 2385);
DISPLAY 0.808511 (-4285 2385);
PAINT MONO (-4285 2385);
FORCEPROP 0 LASTPIN (-4275 2425) $PN 43
J 2
(-4285 2435);
DISPLAY 0.808511 (-4285 2435);
PAINT MONO (-4285 2435);
FORCEPROP 0 LASTPIN (-4275 2475) $PN 41
J 2
(-4285 2485);
DISPLAY 0.808511 (-4285 2485);
PAINT MONO (-4285 2485);
FORCEPROP 0 LASTPIN (-4275 2625) $PN 35
J 2
(-4285 2635);
DISPLAY 0.808511 (-4285 2635);
PAINT MONO (-4285 2635);
FORCEPROP 0 LASTPIN (-4275 2675) $PN 33
J 2
(-4285 2685);
DISPLAY 0.808511 (-4285 2685);
PAINT MONO (-4285 2685);
FORCEPROP 0 LASTPIN (-4275 2725) $PN 31
J 2
(-4285 2735);
DISPLAY 0.808511 (-4285 2735);
PAINT MONO (-4285 2735);
FORCEPROP 0 LASTPIN (-4275 2775) $PN 29
J 2
(-4285 2785);
DISPLAY 0.808511 (-4285 2785);
PAINT MONO (-4285 2785);
FORCEPROP 0 LASTPIN (-4275 2825) $PN 27
J 2
(-4285 2835);
DISPLAY 0.808511 (-4285 2835);
PAINT MONO (-4285 2835);
FORCEPROP 0 LASTPIN (-4275 2875) $PN 25
J 2
(-4285 2885);
DISPLAY 0.808511 (-4285 2885);
PAINT MONO (-4285 2885);
FORCEPROP 0 LASTPIN (-4275 2925) $PN 23
J 2
(-4285 2935);
DISPLAY 0.808511 (-4285 2935);
PAINT MONO (-4285 2935);
FORCEPROP 0 LASTPIN (-4275 2975) $PN 21
J 2
(-4285 2985);
DISPLAY 0.808511 (-4285 2985);
PAINT MONO (-4285 2985);
FORCEPROP 0 LASTPIN (-4275 3025) $PN 19
J 2
(-4285 3035);
DISPLAY 0.808511 (-4285 3035);
PAINT MONO (-4285 3035);
FORCEPROP 0 LASTPIN (-4275 3075) $PN 17
J 2
(-4285 3085);
DISPLAY 0.808511 (-4285 3085);
PAINT MONO (-4285 3085);
FORCEPROP 0 LASTPIN (-4275 3125) $PN 15
J 2
(-4285 3135);
DISPLAY 0.808511 (-4285 3135);
PAINT MONO (-4285 3135);
FORCEPROP 0 LASTPIN (-4275 3175) $PN 13
J 2
(-4285 3185);
DISPLAY 0.808511 (-4285 3185);
PAINT MONO (-4285 3185);
FORCEPROP 0 LASTPIN (-4275 3225) $PN 11
J 2
(-4285 3235);
DISPLAY 0.808511 (-4285 3235);
PAINT MONO (-4285 3235);
FORCEPROP 0 LASTPIN (-4275 3275) $PN 9
J 2
(-4285 3285);
DISPLAY 0.808511 (-4285 3285);
PAINT MONO (-4285 3285);
FORCEPROP 0 LASTPIN (-3775 3425) $PN 4
J 0
(-3765 3435);
DISPLAY 0.808511 (-3765 3435);
PAINT MONO (-3765 3435);
FORCEPROP 0 LASTPIN (-4275 3325) $PN 7
J 2
(-4285 3335);
DISPLAY 0.808511 (-4285 3335);
PAINT MONO (-4285 3335);
FORCEPROP 0 LASTPIN (-4275 3375) $PN 5
J 2
(-4285 3385);
DISPLAY 0.808511 (-4285 3385);
PAINT MONO (-4285 3385);
FORCEPROP 0 LASTPIN (-4275 3425) $PN 3
J 2
(-4285 3435);
DISPLAY 0.808511 (-4285 3435);
PAINT MONO (-4285 3435);
FORCEPROP 0 LASTPIN (-4275 3525) $PN 1
J 2
(-4285 3535);
DISPLAY 0.808511 (-4285 3535);
PAINT MONO (-4285 3535);
FORCEPROP 1 LAST LOCATION CONX8
J 0
(-4130 3705);
DISPLAY 0.617021 (-4130 3705);
PAINT GREEN (-4130 3705);
FORCEPROP 0 LASTPIN (-3775 3325) $PN 8
J 0
(-3765 3335);
DISPLAY 0.808511 (-3765 3335);
PAINT MONO (-3765 3335);
FORCEPROP 0 LASTPIN (-3775 3375) $PN 6
J 0
(-3765 3385);
DISPLAY 0.808511 (-3765 3385);
PAINT MONO (-3765 3385);
FORCEPROP 0 LASTPIN (-3775 3525) $PN 2
J 0
(-3765 3535);
DISPLAY 0.808511 (-3765 3535);
PAINT MONO (-3765 3535);
FORCEPROP 0 LASTPIN (-4275 2575) $PN 37
J 2
(-4285 2585);
DISPLAY 0.808511 (-4285 2585);
PAINT MONO (-4285 2585);
FORCEPROP 0 LASTPIN (-4275 2525) $PN 39
J 2
(-4285 2535);
DISPLAY 0.808511 (-4285 2535);
PAINT MONO (-4285 2535);
FORCEPROP 0 LASTPIN (-4275 2025) $PN 59
J 2
(-4285 2035);
DISPLAY 0.808511 (-4285 2035);
PAINT MONO (-4285 2035);
FORCEPROP 0 LASTPIN (-4275 2125) $PN 55
J 2
(-4285 2135);
DISPLAY 0.808511 (-4285 2135);
PAINT MONO (-4285 2135);
FORCEPROP 0 LASTPIN (-4275 2175) $PN 53
J 2
(-4285 2185);
DISPLAY 0.808511 (-4285 2185);
PAINT MONO (-4285 2185);
FORCEPROP 1 LAST PATH I48
J 0
(-4025 2775);
DISPLAY 0.617021 (-4025 2775);
PAINT GREEN (-4025 2775);
DISPLAY INVISIBLE (-4025 2775);
FORCEPROP 0 LAST CDS_SEC 1
J 0
(-4125 3750);
PAINT MONO (-4125 3750);
DISPLAY INVISIBLE (-4125 3750);
FORCEPROP 0 LAST $SEC 1
J 0
(-4125 3750);
PAINT MONO (-4125 3750);
DISPLAY INVISIBLE (-4125 3750);
FORCEPROP 0 LAST CDS_LOCATION CONX8
J 0
(-4125 3750);
PAINT MONO (-4125 3750);
DISPLAY INVISIBLE (-4125 3750);
FORCEPROP 1 LAST CDS_LMAN_SYM_OUTLINE -100,900,100,-900
J 0
(-4025 2775);
DISPLAY 0.468085 (-4025 2775);
PAINT GREEN (-4025 2775);
DISPLAY INVISIBLE (-4025 2775);
FORCEPROP 2 LAST CDS_LIB w_hdl
J 0
(-4025 2775);
PAINT MONO (-4025 2775);
DISPLAY INVISIBLE (-4025 2775);
FORCEPROP 1 LAST PART_NUMBER 020.C0082.0060
J 0
(-4025 2775);
DISPLAY 0.617021 (-4025 2775);
PAINT GREEN (-4025 2775);
DISPLAY INVISIBLE (-4025 2775);
FORCEPROP 1 LAST PACK_TYPE CONN-G7
J 0
(-4025 2775);
DISPLAY 0.617021 (-4025 2775);
PAINT GREEN (-4025 2775);
DISPLAY INVISIBLE (-4025 2775);
FORCEADD TAP..1
R 2
(-5300 2325);
FORCEPROP 3 LASTPIN (-5250 2325) SIG_NAME P3E_CPU0_PE2_SS_C_TXP<15>
J 0
(-5240 2335);
DISPLAY 0.659574 (-5240 2335);
PAINT MONO (-5240 2335);
DISPLAY INVISIBLE (-5240 2335);
FORCEPROP 1 LASTPIN (-5250 2325) BN 15
J 2
(-5238 2333);
DISPLAY 0.680851 (-5238 2333);
PAINT GREEN (-5238 2333);
FORCEPROP 1 LAST HDL_TAP TRUE
J 2
(-5625 2200);
DISPLAY 0.872340 (-5625 2200);
PAINT ORANGE (-5625 2200);
DISPLAY INVISIBLE (-5625 2200);
FORCEPROP 1 LAST BODY_TYPE PLUMBING
J 2
(-5300 2375);
DISPLAY 0.872340 (-5300 2375);
PAINT GREEN (-5300 2375);
DISPLAY INVISIBLE (-5300 2375);
FORCEPROP 1 LAST PATH I5
J 2
(-5298 2325);
DISPLAY 0.872340 (-5298 2325);
PAINT GREEN (-5298 2325);
DISPLAY INVISIBLE (-5298 2325);
FORCEPROP 2 LAST CDS_LIB mstr_standard
J 0
(-5300 2325);
PAINT MONO (-5300 2325);
DISPLAY INVISIBLE (-5300 2325);
FORCEADD TAP..1
R 2
(-5925 2375);
FORCEPROP 3 LASTPIN (-5875 2375) SIG_NAME P3E_CPU0_PE2_SS_C_TXN<15>
J 0
(-5865 2385);
DISPLAY 0.659574 (-5865 2385);
PAINT MONO (-5865 2385);
DISPLAY INVISIBLE (-5865 2385);
FORCEPROP 1 LASTPIN (-5875 2375) BN 15
J 2
(-5863 2383);
DISPLAY 0.680851 (-5863 2383);
PAINT GREEN (-5863 2383);
FORCEPROP 1 LAST HDL_TAP TRUE
J 2
(-6250 2250);
DISPLAY 0.872340 (-6250 2250);
PAINT ORANGE (-6250 2250);
DISPLAY INVISIBLE (-6250 2250);
FORCEPROP 1 LAST BODY_TYPE PLUMBING
J 2
(-5925 2425);
DISPLAY 0.872340 (-5925 2425);
PAINT GREEN (-5925 2425);
DISPLAY INVISIBLE (-5925 2425);
FORCEPROP 1 LAST PATH I6
J 2
(-5923 2375);
DISPLAY 0.872340 (-5923 2375);
PAINT GREEN (-5923 2375);
DISPLAY INVISIBLE (-5923 2375);
FORCEPROP 2 LAST CDS_LIB mstr_standard
J 0
(-5925 2375);
PAINT MONO (-5925 2375);
DISPLAY INVISIBLE (-5925 2375);
FORCEADD TAP..1
R 2
(-5925 2475);
FORCEPROP 3 LASTPIN (-5875 2475) SIG_NAME P3E_CPU0_PE2_SS_C_TXN<14>
J 0
(-5865 2485);
DISPLAY 0.659574 (-5865 2485);
PAINT MONO (-5865 2485);
DISPLAY INVISIBLE (-5865 2485);
FORCEPROP 1 LASTPIN (-5875 2475) BN 14
J 2
(-5863 2483);
DISPLAY 0.680851 (-5863 2483);
PAINT GREEN (-5863 2483);
FORCEPROP 1 LAST HDL_TAP TRUE
J 2
(-6250 2350);
DISPLAY 0.872340 (-6250 2350);
PAINT ORANGE (-6250 2350);
DISPLAY INVISIBLE (-6250 2350);
FORCEPROP 1 LAST BODY_TYPE PLUMBING
J 2
(-5925 2525);
DISPLAY 0.872340 (-5925 2525);
PAINT GREEN (-5925 2525);
DISPLAY INVISIBLE (-5925 2525);
FORCEPROP 1 LAST PATH I7
J 2
(-5923 2475);
DISPLAY 0.872340 (-5923 2475);
PAINT GREEN (-5923 2475);
DISPLAY INVISIBLE (-5923 2475);
FORCEPROP 2 LAST CDS_LIB mstr_standard
J 0
(-5925 2475);
PAINT MONO (-5925 2475);
DISPLAY INVISIBLE (-5925 2475);
FORCEADD TAP..1
R 2
(-5925 2825);
FORCEPROP 3 LASTPIN (-5875 2825) SIG_NAME P3E_CPU0_PE2_SS_C_TXN<12>
J 0
(-5865 2835);
DISPLAY 0.659574 (-5865 2835);
PAINT MONO (-5865 2835);
DISPLAY INVISIBLE (-5865 2835);
FORCEPROP 1 LASTPIN (-5875 2825) BN 12
J 2
(-5863 2833);
DISPLAY 0.680851 (-5863 2833);
PAINT GREEN (-5863 2833);
FORCEPROP 1 LAST HDL_TAP TRUE
J 2
(-6250 2700);
DISPLAY 0.872340 (-6250 2700);
PAINT ORANGE (-6250 2700);
DISPLAY INVISIBLE (-6250 2700);
FORCEPROP 1 LAST BODY_TYPE PLUMBING
J 2
(-5925 2875);
DISPLAY 0.872340 (-5925 2875);
PAINT GREEN (-5925 2875);
DISPLAY INVISIBLE (-5925 2875);
FORCEPROP 1 LAST PATH I8
J 2
(-5923 2825);
DISPLAY 0.872340 (-5923 2825);
PAINT GREEN (-5923 2825);
DISPLAY INVISIBLE (-5923 2825);
FORCEPROP 2 LAST CDS_LIB mstr_standard
J 0
(-5925 2825);
PAINT MONO (-5925 2825);
DISPLAY INVISIBLE (-5925 2825);
FORCEADD TAP..1
R 2
(-5925 2675);
FORCEPROP 3 LASTPIN (-5875 2675) SIG_NAME P3E_CPU0_PE2_SS_C_TXN<13>
J 0
(-5865 2685);
DISPLAY 0.659574 (-5865 2685);
PAINT MONO (-5865 2685);
DISPLAY INVISIBLE (-5865 2685);
FORCEPROP 1 LASTPIN (-5875 2675) BN 13
J 2
(-5863 2683);
DISPLAY 0.680851 (-5863 2683);
PAINT GREEN (-5863 2683);
FORCEPROP 1 LAST HDL_TAP TRUE
J 2
(-6250 2550);
DISPLAY 0.872340 (-6250 2550);
PAINT ORANGE (-6250 2550);
DISPLAY INVISIBLE (-6250 2550);
FORCEPROP 1 LAST BODY_TYPE PLUMBING
J 2
(-5925 2725);
DISPLAY 0.872340 (-5925 2725);
PAINT GREEN (-5925 2725);
DISPLAY INVISIBLE (-5925 2725);
FORCEPROP 1 LAST PATH I9
J 2
(-5923 2675);
DISPLAY 0.872340 (-5923 2675);
PAINT GREEN (-5923 2675);
DISPLAY INVISIBLE (-5923 2675);
FORCEPROP 2 LAST CDS_LIB mstr_standard
J 0
(-5925 2675);
PAINT MONO (-5925 2675);
DISPLAY INVISIBLE (-5925 2675);
FORCEADD INTEL_CORP_BPAGE..1
(0 0);
FORCEPROP 1 LAST CDS_CON_LAST_MODIFIED Tue Dec 01 11:52:32 2015
J 0
(-1425 325);
PAINT ORANGE (-1425 325);
DISPLAY INVISIBLE (-1425 325);
FORCEPROP 1 LAST CUSTOM_TXT_CDS <CURRENT_DESIGN_SHEET> OF <TOTAL_DESIGN_SHEETS>
J 0
(-500 25);
PAINT GREEN (-500 25);
FORCEPROP 1 LAST CUSTOM_TXT_CDS <CON_LAST_MODIFIED>
J 0
(-1925 350);
PAINT GREEN (-1925 350);
FORCEPROP 2 LAST CUSTOM_TXT_CDS <XR_PAGE_TITLE>
J 0
(-7890 5250);
DISPLAY 0.638298 (-7890 5250);
PAINT PINK (-7890 5250);
DISPLAY INVISIBLE (-7890 5250);
FORCEPROP 1 LAST SCH_TITLE x8 PCIe Riser Connector
J 0
(-7950 50);
DISPLAY 2.468085 (-7950 50);
PAINT ORANGE (-7950 50);
FORCEPROP 1 LAST SCH_NUMBER 000000-000
J 0
(-1300 150);
DISPLAY 1.702128 (-1300 150);
PAINT GREEN (-1300 150);
FORCEPROP 1 LAST SCH_REV 0.1
J 0
(-250 150);
DISPLAY 1.170213 (-250 150);
PAINT GREEN (-250 150);
FORCEPROP 1 LAST SCH_DEPT UNKNOWN
J 1
(-4450 100);
DISPLAY 1.255319 (-4450 100);
PAINT ORANGE (-4450 100);
FORCEPROP 1 LAST SCH_ADDRESS3 Santa Clara, CA 95052-8119
J 0
(-3975 25);
DISPLAY 0.872340 (-3975 25);
PAINT GREEN (-3975 25);
FORCEPROP 1 LAST SCH_ADDRESS2 P.O. BOX 58119
J 0
(-3975 75);
DISPLAY 0.872340 (-3975 75);
PAINT GREEN (-3975 75);
FORCEPROP 1 LAST SCH_ADDRESS1 2200 Mission College Blvd.
J 0
(-3975 125);
DISPLAY 0.872340 (-3975 125);
PAINT GREEN (-3975 125);
FORCEPROP 1 LAST COMMENT_BODY TRUE
J 0
(12 12);
DISPLAY 0.468085 (12 12);
PAINT GREEN (12 12);
DISPLAY INVISIBLE (12 12);
FORCEPROP 2 LAST CDS_LIB mstr_symbols
J 0
(0 0);
PAINT MONO (0 0);
DISPLAY INVISIBLE (0 0);
FORCEPROP 2 LAST PAGE_BORDER TRUE
J 0
(-7890 5250);
DISPLAY 0.638298 (-7890 5250);
PAINT PINK (-7890 5250);
DISPLAY INVISIBLE (-7890 5250);
FORCEPROP 2 LAST CDS_XR_PAGE_TITLE CR-245 : @BASEBOARD_FAB2_LIB.BASEBOARD_FAB2(SCH_1):PAGE245
J 0
(-7890 5250);
DISPLAY 0.638298 (-7890 5250);
PAINT PINK (-7890 5250);
DISPLAY INVISIBLE (-7890 5250);
WIRE 17 -1 (-5350 2550)(-5350 2350);
WIRE 17 -1 (-5350 2650)(-5350 2550);
WIRE 17 -1 (-5350 2800)(-5350 2650);
WIRE 17 -1 (-5350 3000)(-5350 2800);
WIRE 17 -1 (-5350 3100)(-5350 3000);
WIRE 17 -1 (-5350 3250)(-5350 3100);
WIRE 17 -1 (-5350 3450)(-5350 3250);
WIRE 17 -1 (-5350 3550)(-5350 3450);
WIRE 17 -1 (-5350 3550)(-6875 3550);
FORCEPROP 2 LAST SIG_NAME P3E_CPU0_PE2_SS_C_TXP<15:8>
J 0
(-6835 3560);
DISPLAY 0.617021 (-6835 3560);
PAINT ORANGE (-6835 3560);
WIRE 17 -1 (-5975 2700)(-5975 2500);
WIRE 17 -1 (-5975 2850)(-5975 2700);
WIRE 17 -1 (-5975 2500)(-5975 2400);
WIRE 17 -1 (-5975 2950)(-5975 2850);
WIRE 17 -1 (-5975 2950)(-5975 3150);
WIRE 17 -1 (-5975 3150)(-5975 3300);
WIRE 17 -1 (-5975 3400)(-5975 3300);
WIRE 17 -1 (-5975 3775)(-5975 3400);
WIRE 17 -1 (-5975 3775)(-6875 3775);
FORCEPROP 2 LAST SIG_NAME P3E_CPU0_PE2_SS_C_TXN<15:8>
J 0
(-6835 3785);
DISPLAY 0.617021 (-6835 3785);
PAINT ORANGE (-6835 3785);
WIRE 17 -1 (-2250 2450)(-2250 2650);
WIRE 17 -1 (-2250 2300)(-2250 2450);
WIRE 17 -1 (-2250 2650)(-2250 2750);
WIRE 17 -1 (-2250 2750)(-2250 2900);
WIRE 17 -1 (-2250 3050)(-2250 2900);
WIRE 17 -1 (-2250 3050)(-2250 3200);
WIRE 17 -1 (-2250 3350)(-2250 3200);
WIRE 17 -1 (-2250 3475)(-2250 3350);
WIRE 17 -1 (-2250 3475)(-1325 3475);
FORCEPROP 2 LAST SIG_NAME P3E_CPU0_PE2_SS_RXP<15:8>
J 0
(-2210 3485);
DISPLAY 0.617021 (-2210 3485);
PAINT ORANGE (-2210 3485);
WIRE 17 -1 (-2450 2800)(-2450 2950);
WIRE 17 -1 (-2450 2600)(-2450 2800);
WIRE 17 -1 (-2450 2950)(-2450 3100);
WIRE 17 -1 (-2450 3100)(-2450 3250);
WIRE 17 -1 (-2450 2500)(-2450 2600);
WIRE 17 -1 (-2450 2350)(-2450 2500);
WIRE 17 -1 (-2450 3250)(-2450 3400);
WIRE 17 -1 (-2450 3600)(-2450 3400);
WIRE 17 -1 (-2450 3600)(-1325 3600);
FORCEPROP 2 LAST SIG_NAME P3E_CPU0_PE2_SS_RXN<15:8>
J 0
(-2185 3610);
DISPLAY 0.617021 (-2185 3610);
PAINT ORANGE (-2185 3610);
WIRE 16 -1 (-4750 3525)(-4275 3525);
WIRE 16 -1 (-4750 3525)(-4750 3325);
WIRE 16 -1 (-4275 3325)(-4750 3325);
WIRE 16 -1 (-4750 3175)(-4750 3325);
WIRE 16 -1 (-4750 3175)(-4275 3175);
WIRE 16 -1 (-4750 3025)(-4750 3175);
WIRE 16 -1 (-4750 3025)(-4275 3025);
WIRE 16 -1 (-4750 2875)(-4750 3025);
WIRE 16 -1 (-4750 2875)(-4275 2875);
WIRE 16 -1 (-4750 2725)(-4750 2875);
WIRE 16 -1 (-4750 2725)(-4275 2725);
WIRE 16 -1 (-4750 2575)(-4750 2725);
WIRE 16 -1 (-4750 2575)(-4275 2575);
WIRE 16 -1 (-4750 2425)(-4750 2575);
WIRE 16 -1 (-4750 2425)(-4275 2425);
WIRE 16 -1 (-4750 2275)(-4750 2425);
WIRE 16 -1 (-4750 2275)(-4275 2275);
WIRE 16 -1 (-4750 2125)(-4750 2275);
WIRE 16 -1 (-4275 2125)(-4750 2125);
WIRE 16 -1 (-4750 1875)(-4750 2125);
WIRE 16 -1 (-4275 1925)(-4300 1925);
WIRE 16 -1 (-4300 1925)(-4300 1675);
WIRE 16 -1 (-4175 3575)(-4350 3575);
WIRE 16 -1 (-4350 3575)(-4350 3625);
WIRE 16 -1 (-4275 3625)(-4350 3625);
WIRE 16 -1 (-4350 3625)(-4450 3625);
WIRE 16 -1 (-3875 1975)(-3700 1975);
WIRE 16 -1 (-3700 1675)(-3700 1975);
WIRE 16 -1 (-3775 3425)(-3400 3425);
WIRE 16 -1 (-3400 3425)(-3400 3275);
WIRE 16 -1 (-3775 3275)(-3400 3275);
WIRE 16 -1 (-3400 3275)(-3400 3125);
WIRE 16 -1 (-3775 3125)(-3400 3125);
WIRE 16 -1 (-3400 3125)(-3400 2975);
WIRE 16 -1 (-3775 2975)(-3400 2975);
WIRE 16 -1 (-3400 2975)(-3400 2825);
WIRE 16 -1 (-3775 2825)(-3400 2825);
WIRE 16 -1 (-3400 2825)(-3400 2675);
WIRE 16 -1 (-3775 2675)(-3400 2675);
WIRE 16 -1 (-3400 2675)(-3400 2525);
WIRE 16 -1 (-3775 2525)(-3400 2525);
WIRE 16 -1 (-3400 2525)(-3400 2375);
WIRE 16 -1 (-3775 2375)(-3400 2375);
WIRE 16 -1 (-3400 2375)(-3400 2225);
WIRE 16 -1 (-3775 2225)(-3400 2225);
WIRE 16 -1 (-3400 2225)(-3400 2075);
WIRE 16 -1 (-3775 2075)(-3400 2075);
FORCEPROP 0 LAST VOLTAGE 0
J 0
(-3837 2075);
PAINT MONO (-3837 2075);
DISPLAY INVISIBLE (-3837 2075);
FORCEPROP 0 LAST CDS_PHYS_NET_NAME GND
J 0
(-3837 2122);
PAINT MONO (-3837 2122);
DISPLAY INVISIBLE (-3837 2122);
FORCEPROP 0 LAST ROOM TBD
J 0
(-3837 2169);
PAINT MONO (-3837 2169);
DISPLAY INVISIBLE (-3837 2169);
FORCEPROP 0 LAST BOM_COST TBD
J 0
(-3837 2216);
PAINT MONO (-3837 2216);
DISPLAY INVISIBLE (-3837 2216);
WIRE 16 -1 (-3400 2075)(-3400 1675);
WIRE 3 2175 (-7350 4675)(-675 4675);
WIRE 3 2175 (-7350 4675)(-7350 925);
WIRE 3 2175 (-675 4675)(-675 925);
WIRE 3 2175 (-7350 925)(-675 925);
WIRE 16 -1 (-5450 2175)(-4275 2175);
FORCEPROP 0 LAST SIG_NAME CLK_100M_SRC12_DN
J 0
(-5380 2185);
DISPLAY 0.617021 (-5380 2185);
PAINT ORANGE (-5380 2185);
WIRE 16 -1 (-5450 2075)(-4275 2075);
FORCEPROP 0 LAST SIG_NAME USB2_P02_DP
J 1
(-5225 2085);
DISPLAY 0.617021 (-5225 2085);
PAINT ORANGE (-5225 2085);
WIRE 16 -1 (-5450 2025)(-4275 2025);
FORCEPROP 0 LAST SIG_NAME USB2_P02_DN
J 1
(-5225 2035);
DISPLAY 0.617021 (-5225 2035);
PAINT ORANGE (-5225 2035);
WIRE 16 -1 (-3775 2575)(-2550 2575);
WIRE 16 -1 (-3775 2475)(-2550 2475);
WIRE 16 -1 (-3775 2325)(-2550 2325);
WIRE 16 -1 (-3775 2275)(-2350 2275);
WIRE 16 -1 (-3775 2175)(-2925 2175);
FORCEPROP 0 LAST SIG_NAME CLK_100M_SRC13_DP
J 0
(-3355 2185);
DISPLAY 0.617021 (-3355 2185);
PAINT ORANGE (-3355 2185);
WIRE 16 -1 (-5450 2225)(-4275 2225);
FORCEPROP 0 LAST SIG_NAME CLK_100M_SRC12_DP
J 0
(-5380 2235);
DISPLAY 0.617021 (-5380 2235);
PAINT ORANGE (-5380 2235);
WIRE 16 -1 (-3775 2625)(-2350 2625);
WIRE 16 -1 (-3775 3375)(-2550 3375);
FORCEPROP 0 LAST CDS_PHYS_NET_NAME P3E_CPU0_PE2_SS_RXN<8>
J 0
(-3050 3375);
PAINT MONO (-3050 3375);
DISPLAY INVISIBLE (-3050 3375);
WIRE 16 -1 (-3775 2125)(-2925 2125);
FORCEPROP 0 LAST SIG_NAME CLK_100M_SRC13_DN
J 0
(-3355 2135);
DISPLAY 0.617021 (-3355 2135);
PAINT ORANGE (-3355 2135);
WIRE 16 -1 (-3775 2725)(-2350 2725);
WIRE 16 -1 (-3775 2775)(-2550 2775);
WIRE 16 -1 (-3775 2875)(-2350 2875);
WIRE 16 -1 (-3775 3075)(-2550 3075);
WIRE 16 -1 (-3775 3225)(-2550 3225);
WIRE 16 -1 (-3775 3325)(-2350 3325);
FORCEPROP 0 LAST CDS_PHYS_NET_NAME P3E_CPU0_PE2_SS_RXP<8>
J 0
(-3175 3325);
PAINT MONO (-3175 3325);
DISPLAY INVISIBLE (-3175 3325);
WIRE 16 -1 (-3775 2925)(-2550 2925);
WIRE 16 -1 (-3775 3025)(-2350 3025);
WIRE 16 -1 (-3775 3175)(-2350 3175);
WIRE 16 -1 (-4275 3425)(-5250 3425);
WIRE 16 -1 (-4275 3375)(-5875 3375);
WIRE 16 -1 (-5250 3225)(-4275 3225);
WIRE 16 -1 (-5875 3275)(-4275 3275);
WIRE 16 -1 (-3775 2425)(-2350 2425);
WIRE 16 -1 (-5875 2375)(-4275 2375);
WIRE 16 -1 (-5250 2525)(-4275 2525);
WIRE 16 -1 (-5250 2625)(-4275 2625);
WIRE 16 -1 (-5250 3075)(-4275 3075);
WIRE 16 -1 (-5875 3125)(-4275 3125);
WIRE 16 -1 (-5250 2975)(-4275 2975);
WIRE 16 -1 (-5875 2925)(-4275 2925);
WIRE 16 -1 (-5875 2825)(-4275 2825);
WIRE 16 -1 (-5250 2775)(-4275 2775);
WIRE 16 -1 (-5875 2675)(-4275 2675);
WIRE 16 -1 (-5875 2475)(-4275 2475);
WIRE 16 -1 (-5250 2325)(-4275 2325);
DOT 1 (-4750 2125);
DOT 1 (-3400 3275);
DOT 1 (-3400 3125);
DOT 1 (-3400 2975);
DOT 1 (-3400 2825);
DOT 1 (-3400 2675);
DOT 1 (-3400 2375);
DOT 1 (-3400 2525);
DOT 1 (-3400 2075);
DOT 1 (-3400 2225);
DOT 1 (-4350 3625);
DOT 1 (-4750 3175);
DOT 1 (-4750 3325);
DOT 1 (-4750 2875);
DOT 1 (-4750 2725);
DOT 1 (-4750 2425);
DOT 1 (-4750 2575);
DOT 1 (-4750 2275);
DOT 1 (-4750 3025);
FORCENOTE
NEW ADD
(-2525 2150) 0;
DISPLAY LEFT (-2525 2150);
DISPLAY 1.021277 (-2525 2150);
PAINT PURPLE (-2525 2150);
FORCENOTE
NEW ADD
(-6425 2075) 0;
DISPLAY LEFT (-6425 2075);
DISPLAY 1.021277 (-6425 2075);
PAINT PURPLE (-6425 2075);
FORCENOTE
NEW ADD
(-6400 2175) 0;
DISPLAY LEFT (-6400 2175);
DISPLAY 1.021277 (-6400 2175);
PAINT PURPLE (-6400 2175);
FORCENOTE
TP FAB1 ADD X8 CONNECTOR
(-4525 1150) 0;
DISPLAY LEFT (-4525 1150);
DISPLAY 1.702128 (-4525 1150);
PAINT RED (-4525 1150);
QUIT
